# S9S_MB_2U (Grand Teton) — schematic netlist excerpt (pin names and nets, part order shuffled) for the footprints in the layout excerpt that follows; sources: Cadence DE-HDL packaged netlist, KiCad conversion of 03242023_DA0F0TMBIJ0_F0T_Motherboard_J_brd_V01_OCP.brd

C1834  Q_CAP  0.1UF 25V 10% X7R  pkg 0402  page 159 : A = P12V_OCP_V3_2 ; B = GND
R265  Q_RES  240 1% CHIP  pkg 0402LF  page 119 : A = PVNN_TERM_CPU1 ; B = PU_CPU1_SOCKET_ID0

(kicad_pcb
	(version 20260206)
	(generator "pcbnew")
	(generator_version "10.0")
	(general
		(thickness 1.6)
		(legacy_teardrops no)
	)
	(paper "A4")
	(title_block
		(title "03242023_DA0F0TMBIJ0_F0T_Motherboard_J_brd_V01_OCP.brd")
		(comment 1 "Grand Teton / footprints 4883-4884 of 6105")
	)
	(layers
		(0 "F.Cu" signal "TOP")
		(4 "In1.Cu" signal "GND")
		(6 "In2.Cu" signal "IN1")
		(8 "In3.Cu" signal "GND1")
		(10 "In4.Cu" signal "IN2")
		(12 "In5.Cu" signal "GND2")
		(14 "In6.Cu" signal "IN3")
		(16 "In7.Cu" signal "GND3")
		(18 "In8.Cu" signal "VCC")
		(20 "In9.Cu" signal "VCC1")
		(22 "In10.Cu" signal "GND4")
		(24 "In11.Cu" signal "IN4")
		(26 "In12.Cu" signal "GND5")
		(28 "In13.Cu" signal "IN5")
		(30 "In14.Cu" signal "GND6")
		(32 "In15.Cu" signal "IN6")
		(34 "In16.Cu" signal "GND7")
		(2 "B.Cu" signal "BOTTOM")
		(9 "F.Adhes" user "F.Adhesive")
		(11 "B.Adhes" user "B.Adhesive")
		(13 "F.Paste" user "Package Geometry/Pastemask Top")
		(15 "B.Paste" user "Package Geometry/Pastemask Bottom")
		(5 "F.SilkS" user "Ref Des/Silkscreen Top")
		(7 "B.SilkS" user "Ref Des/Silkscreen Bottom")
		(1 "F.Mask" user "Board Geometry/Soldermask Top")
		(3 "B.Mask" user "Board Geometry/Soldermask Bottom")
		(17 "Dwgs.User" user "User.Drawings")
		(19 "Cmts.User" user "User.Comments")
		(21 "Eco1.User" user "User.Eco1")
		(23 "Eco2.User" user "User.Eco2")
		(25 "Edge.Cuts" user "Board Geometry/Outline")
		(27 "Margin" user)
		(31 "F.CrtYd" user "Package Geometry/Place Bound Top")
		(29 "B.CrtYd" user "Package Geometry/Place Bound Bottom")
		(35 "F.Fab" user "Ref Des/Assembly Top")
		(33 "B.Fab" user "Ref Des/Assembly Bottom")
	)
	(footprint ""
		(layer "B.Cu")
		(at 174.997618 -200.403968 -90)
		(property "Reference" "R265"
			(at 0 0 90)
			(layer "B.SilkS")
			(hide yes)
			(effects
				(font
					(size 1.27 1.27)
				)
				(justify mirror)
			)
		)
		(property "Value" ""
			(at 0 0 90)
			(layer "B.Fab")
			(effects
				(font
					(size 1.27 1.27)
				)
				(justify mirror)
			)
		)
		(duplicate_pad_numbers_are_jumpers no)
		(fp_line
			(start -0.7874 0.4064)
			(end 0.7874 0.4064)
			(stroke
				(width 0.1524)
				(type default)
			)
			(layer "B.SilkS")
		)
		(fp_line
			(start 0.7874 0.4064)
			(end 0.7874 -0.4064)
			(stroke
				(width 0.1524)
				(type default)
			)
			(layer "B.SilkS")
		)
		(fp_line
			(start -0.7874 -0.4064)
			(end -0.7874 0.4064)
			(stroke
				(width 0.1524)
				(type default)
			)
			(layer "B.SilkS")
		)
		(fp_line
			(start 0.7874 -0.4064)
			(end -0.7874 -0.4064)
			(stroke
				(width 0.1524)
				(type default)
			)
			(layer "B.SilkS")
		)
		(fp_line
			(start -0.67945 0.3048)
			(end -0.120396 0.3048)
			(stroke
				(width 0.1)
				(type default)
			)
			(layer "B.Fab")
		)
		(fp_line
			(start -0.120396 0.3048)
			(end -0.120396 0.2794)
			(stroke
				(width 0.1)
				(type default)
			)
			(layer "B.Fab")
		)
		(fp_line
			(start 0.12065 0.3048)
			(end 0.67945 0.3048)
			(stroke
				(width 0.1)
				(type default)
			)
			(layer "B.Fab")
		)
		(fp_line
			(start 0.67945 0.3048)
			(end 0.67945 -0.305054)
			(stroke
				(width 0.1)
				(type default)
			)
			(layer "B.Fab")
		)
		(fp_line
			(start -0.120396 0.2794)
			(end 0.12065 0.2794)
			(stroke
				(width 0.1)
				(type default)
			)
			(layer "B.Fab")
		)
		(fp_line
			(start 0.12065 0.2794)
			(end 0.12065 0.3048)
			(stroke
				(width 0.1)
				(type default)
			)
			(layer "B.Fab")
		)
		(fp_line
			(start -0.12065 -0.2794)
			(end -0.12065 -0.3048)
			(stroke
				(width 0.1)
				(type default)
			)
			(layer "B.Fab")
		)
		(fp_line
			(start 0.12065 -0.2794)
			(end -0.12065 -0.2794)
			(stroke
				(width 0.1)
				(type default)
			)
			(layer "B.Fab")
		)
		(fp_line
			(start -0.67945 -0.3048)
			(end -0.67945 0.3048)
			(stroke
				(width 0.1)
				(type default)
			)
			(layer "B.Fab")
		)
		(fp_line
			(start -0.12065 -0.3048)
			(end -0.67945 -0.3048)
			(stroke
				(width 0.1)
				(type default)
			)
			(layer "B.Fab")
		)
		(fp_line
			(start 0.12065 -0.305054)
			(end 0.12065 -0.2794)
			(stroke
				(width 0.1)
				(type default)
			)
			(layer "B.Fab")
		)
		(fp_line
			(start 0.67945 -0.305054)
			(end 0.12065 -0.305054)
			(stroke
				(width 0.1)
				(type default)
			)
			(layer "B.Fab")
		)
		(pad "1" smd circle
			(at 0.40005 0 90)
			(size 0 0)
			(layers "B.Cu" "B.Mask" "B.Paste")
			(net "PVNN_TERM_CPU1")
		)
		(pad "2" smd circle
			(at -0.40005 0 90)
			(size 0 0)
			(layers "B.Cu" "B.Mask" "B.Paste")
			(net "PU_CPU1_SOCKET_ID0")
		)
	)
	(footprint ""
		(layer "B.Cu")
		(at 66.149982 -15.32763)
		(property "Reference" "C1834"
			(at 0 0 0)
			(layer "B.SilkS")
			(hide yes)
			(effects
				(font
					(size 1.27 1.27)
				)
				(justify mirror)
			)
		)
		(property "Value" ""
			(at 0 0 0)
			(layer "B.Fab")
			(effects
				(font
					(size 1.27 1.27)
				)
				(justify mirror)
			)
		)
		(duplicate_pad_numbers_are_jumpers no)
		(fp_line
			(start -0.7874 -0.4064)
			(end -0.7874 0.4064)
			(stroke
				(width 0.1524)
				(type default)
			)
			(layer "B.SilkS")
		)
		(fp_line
			(start -0.7874 0.4064)
			(end 0.7874 0.4064)
			(stroke
				(width 0.1524)
				(type default)
			)
			(layer "B.SilkS")
		)
		(fp_line
			(start 0.7874 -0.4064)
			(end -0.7874 -0.4064)
			(stroke
				(width 0.1524)
				(type default)
			)
			(layer "B.SilkS")
		)
		(fp_line
			(start 0.7874 0.4064)
			(end 0.7874 -0.4064)
			(stroke
				(width 0.1524)
				(type default)
			)
			(layer "B.SilkS")
		)
		(fp_line
			(start -0.67945 -0.3048)
			(end -0.67945 0.3048)
			(stroke
				(width 0.1)
				(type default)
			)
			(layer "B.Fab")
		)
		(fp_line
			(start -0.67945 0.3048)
			(end -0.120396 0.3048)
			(stroke
				(width 0.1)
				(type default)
			)
			(layer "B.Fab")
		)
		(fp_line
			(start -0.12065 -0.3048)
			(end -0.67945 -0.3048)
			(stroke
				(width 0.1)
				(type default)
			)
			(layer "B.Fab")
		)
		(fp_line
			(start -0.12065 -0.2794)
			(end -0.12065 -0.3048)
			(stroke
				(width 0.1)
				(type default)
			)
			(layer "B.Fab")
		)
		(fp_line
			(start -0.120396 0.2794)
			(end 0.12065 0.2794)
			(stroke
				(width 0.1)
				(type default)
			)
			(layer "B.Fab")
		)
		(fp_line
			(start -0.120396 0.3048)
			(end -0.120396 0.2794)
			(stroke
				(width 0.1)
				(type default)
			)
			(layer "B.Fab")
		)
		(fp_line
			(start 0.12065 -0.305054)
			(end 0.12065 -0.2794)
			(stroke
				(width 0.1)
				(type default)
			)
			(layer "B.Fab")
		)
		(fp_line
			(start 0.12065 -0.2794)
			(end -0.12065 -0.2794)
			(stroke
				(width 0.1)
				(type default)
			)
			(layer "B.Fab")
		)
		(fp_line
			(start 0.12065 0.2794)
			(end 0.12065 0.3048)
			(stroke
				(width 0.1)
				(type default)
			)
			(layer "B.Fab")
		)
		(fp_line
			(start 0.12065 0.3048)
			(end 0.67945 0.3048)
			(stroke
				(width 0.1)
				(type default)
			)
			(layer "B.Fab")
		)
		(fp_line
			(start 0.67945 -0.305054)
			(end 0.12065 -0.305054)
			(stroke
				(width 0.1)
				(type default)
			)
			(layer "B.Fab")
		)
		(fp_line
			(start 0.67945 0.3048)
			(end 0.67945 -0.305054)
			(stroke
				(width 0.1)
				(type default)
			)
			(layer "B.Fab")
		)
		(pad "1" smd circle
			(at 0.40005 0 180)
			(size 0 0)
			(layers "B.Cu" "B.Mask" "B.Paste")
			(net "P12V_OCP_V3_2")
		)
		(pad "2" smd circle
			(at -0.40005 0 180)
			(size 0 0)
			(layers "B.Cu" "B.Mask" "B.Paste")
			(net "GND")
		)
	)
)
